# T6G (Grand Teton) — schematic netlist excerpt (pin names and nets, part order shuffled) for the footprints in the layout excerpt that follows; sources: Cadence DE-HDL packaged netlist, KiCad conversion of 04192023_DAF0TMB3IC0_F0TG_MB_C_brd_V02_OCP.brd

PR8001  Q_RES  2.2 1% CHIP  pkg 0402LF  page 209 : A = SW_PVDD18_S5_P0_BST ; B = SW_PVDD18_S5_P0_BST_R
R6077  Q_RES  33 5% CHIP  pkg 0402LF  page 151 : A = SMB_SCM_2_R3_SDA ; B = SMB_SCM_2_R4_SDA

(kicad_pcb
	(version 20260206)
	(generator "pcbnew")
	(generator_version "10.0")
	(general
		(thickness 1.6)
		(legacy_teardrops no)
	)
	(paper "A4")
	(title_block
		(title "04192023_DAF0TMB3IC0_F0TG_MB_C_brd_V02_OCP.brd")
		(comment 1 "Grand Teton / footprints 4434-4435 of 8354")
	)
	(layers
		(0 "F.Cu" signal "TOP")
		(4 "In1.Cu" signal "GND")
		(6 "In2.Cu" signal "IN1")
		(8 "In3.Cu" signal "GND1")
		(10 "In4.Cu" signal "IN2")
		(12 "In5.Cu" signal "GND2")
		(14 "In6.Cu" signal "IN3")
		(16 "In7.Cu" signal "GND3")
		(18 "In8.Cu" signal "VCC")
		(20 "In9.Cu" signal "VCC1")
		(22 "In10.Cu" signal "GND4")
		(24 "In11.Cu" signal "IN4")
		(26 "In12.Cu" signal "GND5")
		(28 "In13.Cu" signal "IN5")
		(30 "In14.Cu" signal "GND6")
		(32 "In15.Cu" signal "IN6")
		(34 "In16.Cu" signal "GND7")
		(2 "B.Cu" signal "BOTTOM")
		(9 "F.Adhes" user "F.Adhesive")
		(11 "B.Adhes" user "B.Adhesive")
		(13 "F.Paste" user "Package Geometry/Pastemask Top")
		(15 "B.Paste" user "Package Geometry/Pastemask Bottom")
		(5 "F.SilkS" user "Ref Des/Silkscreen Top")
		(7 "B.SilkS" user "Ref Des/Silkscreen Bottom")
		(1 "F.Mask" user "Board Geometry/Soldermask Top")
		(3 "B.Mask" user "Board Geometry/Soldermask Bottom")
		(17 "Dwgs.User" user "User.Drawings")
		(19 "Cmts.User" user "User.Comments")
		(21 "Eco1.User" user "User.Eco1")
		(23 "Eco2.User" user "User.Eco2")
		(25 "Edge.Cuts" user "Board Geometry/Outline")
		(27 "Margin" user)
		(31 "F.CrtYd" user "Package Geometry/Place Bound Top")
		(29 "B.CrtYd" user "Package Geometry/Place Bound Bottom")
		(35 "F.Fab" user "Ref Des/Assembly Top")
		(33 "B.Fab" user "Ref Des/Assembly Bottom")
	)
	(footprint ""
		(layer "F.Cu")
		(at 332.914498 -143.705834 180)
		(property "Reference" "PR8001"
			(at 0 0 180)
			(layer "F.SilkS")
			(hide yes)
			(effects
				(font
					(size 1.27 1.27)
				)
			)
		)
		(property "Value" ""
			(at 0 0 180)
			(layer "F.Fab")
			(effects
				(font
					(size 1.27 1.27)
				)
			)
		)
		(duplicate_pad_numbers_are_jumpers no)
		(fp_line
			(start 0.7874 0.4064)
			(end -0.7874 0.4064)
			(stroke
				(width 0.1524)
				(type default)
			)
			(layer "F.SilkS")
		)
		(fp_line
			(start 0.7874 -0.4064)
			(end 0.7874 0.4064)
			(stroke
				(width 0.1524)
				(type default)
			)
			(layer "F.SilkS")
		)
		(fp_line
			(start -0.7874 0.4064)
			(end -0.7874 -0.4064)
			(stroke
				(width 0.1524)
				(type default)
			)
			(layer "F.SilkS")
		)
		(fp_line
			(start -0.7874 -0.4064)
			(end 0.7874 -0.4064)
			(stroke
				(width 0.1524)
				(type default)
			)
			(layer "F.SilkS")
		)
		(fp_line
			(start 0.67945 0.3048)
			(end 0.120396 0.3048)
			(stroke
				(width 0.1)
				(type default)
			)
			(layer "F.Fab")
		)
		(fp_line
			(start 0.67945 -0.3048)
			(end 0.67945 0.3048)
			(stroke
				(width 0.1)
				(type default)
			)
			(layer "F.Fab")
		)
		(fp_line
			(start 0.12065 -0.2794)
			(end 0.12065 -0.3048)
			(stroke
				(width 0.1)
				(type default)
			)
			(layer "F.Fab")
		)
		(fp_line
			(start 0.12065 -0.3048)
			(end 0.67945 -0.3048)
			(stroke
				(width 0.1)
				(type default)
			)
			(layer "F.Fab")
		)
		(fp_line
			(start 0.120396 0.3048)
			(end 0.120396 0.2794)
			(stroke
				(width 0.1)
				(type default)
			)
			(layer "F.Fab")
		)
		(fp_line
			(start 0.120396 0.2794)
			(end -0.12065 0.2794)
			(stroke
				(width 0.1)
				(type default)
			)
			(layer "F.Fab")
		)
		(fp_line
			(start -0.12065 0.3048)
			(end -0.67945 0.3048)
			(stroke
				(width 0.1)
				(type default)
			)
			(layer "F.Fab")
		)
		(fp_line
			(start -0.12065 0.2794)
			(end -0.12065 0.3048)
			(stroke
				(width 0.1)
				(type default)
			)
			(layer "F.Fab")
		)
		(fp_line
			(start -0.12065 -0.2794)
			(end 0.12065 -0.2794)
			(stroke
				(width 0.1)
				(type default)
			)
			(layer "F.Fab")
		)
		(fp_line
			(start -0.12065 -0.305054)
			(end -0.12065 -0.2794)
			(stroke
				(width 0.1)
				(type default)
			)
			(layer "F.Fab")
		)
		(fp_line
			(start -0.67945 0.3048)
			(end -0.67945 -0.305054)
			(stroke
				(width 0.1)
				(type default)
			)
			(layer "F.Fab")
		)
		(fp_line
			(start -0.67945 -0.305054)
			(end -0.12065 -0.305054)
			(stroke
				(width 0.1)
				(type default)
			)
			(layer "F.Fab")
		)
		(pad "1" smd circle
			(at -0.40005 0 180)
			(size 0 0)
			(layers "F.Cu" "F.Mask" "F.Paste")
			(net "SW_PVDD18_S5_P0_BST")
		)
		(pad "2" smd circle
			(at 0.40005 0 180)
			(size 0 0)
			(layers "F.Cu" "F.Mask" "F.Paste")
			(net "SW_PVDD18_S5_P0_BST_R")
		)
	)
	(footprint ""
		(layer "F.Cu")
		(at 390.614662 -143.323056 -90)
		(property "Reference" "R6077"
			(at 0 0 270)
			(layer "F.SilkS")
			(hide yes)
			(effects
				(font
					(size 1.27 1.27)
				)
			)
		)
		(property "Value" ""
			(at 0 0 270)
			(layer "F.Fab")
			(effects
				(font
					(size 1.27 1.27)
				)
			)
		)
		(duplicate_pad_numbers_are_jumpers no)
		(fp_line
			(start -0.7874 0.4064)
			(end -0.7874 -0.4064)
			(stroke
				(width 0.1524)
				(type default)
			)
			(layer "F.SilkS")
		)
		(fp_line
			(start 0.7874 0.4064)
			(end -0.7874 0.4064)
			(stroke
				(width 0.1524)
				(type default)
			)
			(layer "F.SilkS")
		)
		(fp_line
			(start -0.7874 -0.4064)
			(end 0.7874 -0.4064)
			(stroke
				(width 0.1524)
				(type default)
			)
			(layer "F.SilkS")
		)
		(fp_line
			(start 0.7874 -0.4064)
			(end 0.7874 0.4064)
			(stroke
				(width 0.1524)
				(type default)
			)
			(layer "F.SilkS")
		)
		(fp_line
			(start -0.67945 0.3048)
			(end -0.67945 -0.305054)
			(stroke
				(width 0.1)
				(type default)
			)
			(layer "F.Fab")
		)
		(fp_line
			(start -0.12065 0.3048)
			(end -0.67945 0.3048)
			(stroke
				(width 0.1)
				(type default)
			)
			(layer "F.Fab")
		)
		(fp_line
			(start 0.120396 0.3048)
			(end 0.120396 0.2794)
			(stroke
				(width 0.1)
				(type default)
			)
			(layer "F.Fab")
		)
		(fp_line
			(start 0.67945 0.3048)
			(end 0.120396 0.3048)
			(stroke
				(width 0.1)
				(type default)
			)
			(layer "F.Fab")
		)
		(fp_line
			(start -0.12065 0.2794)
			(end -0.12065 0.3048)
			(stroke
				(width 0.1)
				(type default)
			)
			(layer "F.Fab")
		)
		(fp_line
			(start 0.120396 0.2794)
			(end -0.12065 0.2794)
			(stroke
				(width 0.1)
				(type default)
			)
			(layer "F.Fab")
		)
		(fp_line
			(start -0.12065 -0.2794)
			(end 0.12065 -0.2794)
			(stroke
				(width 0.1)
				(type default)
			)
			(layer "F.Fab")
		)
		(fp_line
			(start 0.12065 -0.2794)
			(end 0.12065 -0.3048)
			(stroke
				(width 0.1)
				(type default)
			)
			(layer "F.Fab")
		)
		(fp_line
			(start 0.12065 -0.3048)
			(end 0.67945 -0.3048)
			(stroke
				(width 0.1)
				(type default)
			)
			(layer "F.Fab")
		)
		(fp_line
			(start 0.67945 -0.3048)
			(end 0.67945 0.3048)
			(stroke
				(width 0.1)
				(type default)
			)
			(layer "F.Fab")
		)
		(fp_line
			(start -0.67945 -0.305054)
			(end -0.12065 -0.305054)
			(stroke
				(width 0.1)
				(type default)
			)
			(layer "F.Fab")
		)
		(fp_line
			(start -0.12065 -0.305054)
			(end -0.12065 -0.2794)
			(stroke
				(width 0.1)
				(type default)
			)
			(layer "F.Fab")
		)
		(pad "1" smd circle
			(at -0.40005 0 270)
			(size 0 0)
			(layers "F.Cu" "F.Mask" "F.Paste")
			(net "SMB_SCM_2_R3_SDA")
		)
		(pad "2" smd circle
			(at 0.40005 0 270)
			(size 0 0)
			(layers "F.Cu" "F.Mask" "F.Paste")
			(net "SMB_SCM_2_R4_SDA")
		)
	)
)
